(kicad_pcb
	(version 20241229)
	(generator "pcbnew")
	(generator_version "9.0")
	(general
		(thickness 1.6642)
		(legacy_teardrops no)
	)
	(paper "A3")
	(title_block
		(title "PolarFire SoM")
		(date "2025-07-22")
		(rev "1.1.4")
		(company "Antmicro Ltd")
		(comment 1 "www.antmicro.com")
		(comment 9 "footprints 305-309 of 470")
	)
	(layers
		(0 "F.Cu" mixed)
		(4 "In1.Cu" power)
		(6 "In2.Cu" signal)
		(8 "In3.Cu" power)
		(10 "In4.Cu" signal)
		(12 "In5.Cu" power)
		(14 "In6.Cu" power)
		(16 "In7.Cu" signal)
		(18 "In8.Cu" power)
		(20 "In9.Cu" signal)
		(22 "In10.Cu" power)
		(24 "In11.Cu" signal)
		(26 "In12.Cu" signal)
		(2 "B.Cu" mixed)
		(9 "F.Adhes" user "F.Adhesive")
		(11 "B.Adhes" user "B.Adhesive")
		(13 "F.Paste" user)
		(15 "B.Paste" user)
		(5 "F.SilkS" user "F.Silkscreen")
		(7 "B.SilkS" user "B.Silkscreen")
		(1 "F.Mask" user)
		(3 "B.Mask" user)
		(17 "Dwgs.User" user "User.Drawings")
		(19 "Cmts.User" user "User.Comments")
		(21 "Eco1.User" user "User.Eco1")
		(23 "Eco2.User" user "User.Eco2")
		(25 "Edge.Cuts" user)
		(27 "Margin" user)
		(31 "F.CrtYd" user "F.Courtyard")
		(29 "B.CrtYd" user "B.Courtyard")
		(35 "F.Fab" user)
		(33 "B.Fab" user)
	)
	(footprint "antmicro-footprints:R_0402_1005Metric"
		(layer "B.Cu")
		(at 181.9 154.25 90)
		(descr "Resistor SMD 0402")
		(tags "resistor SMD 0402")
		(property "Reference" "R68"
			(at -0.95 -4.75 315)
			(layer "B.SilkS")
			(effects
				(font
					(size 0.7 0.7)
					(thickness 0.15)
				)
				(justify left bottom mirror)
			)
		)
		(property "Value" "R_590R_0402"
			(at -1.011843 -1.772047 270)
			(layer "B.Fab")
			(hide yes)
			(effects
				(font
					(size 0.7 0.7)
					(thickness 0.15)
				)
				(justify left bottom mirror)
			)
		)
		(property "Datasheet" "https://www.bourns.com/docs/product-datasheets/cr.pdf"
			(at 0 0 90)
			(layer "F.Fab")
			(hide yes)
			(effects
				(font
					(size 1.27 1.27)
					(thickness 0.15)
				)
			)
		)
		(property "Description" "SMD Chip Resistor, 590 ohm, ± 1%, 100 mW, 0402 [1005 Metric], Thick Film, Precision"
			(at 0 0 90)
			(layer "F.Fab")
			(hide yes)
			(effects
				(font
					(size 1.27 1.27)
					(thickness 0.15)
				)
			)
		)
		(property "Author" "Antmicro"
			(at 336.15 -27.65 0)
			(layer "B.Fab")
			(hide yes)
			(effects
				(font
					(size 1 1)
					(thickness 0.15)
				)
				(justify mirror)
			)
		)
		(property "License" "Apache-2.0"
			(at 336.15 -27.65 0)
			(layer "B.Fab")
			(hide yes)
			(effects
				(font
					(size 1 1)
					(thickness 0.15)
				)
				(justify mirror)
			)
		)
		(property "MPN" "CR0402-FX-5900GLF"
			(at 336.15 -27.65 0)
			(layer "B.Fab")
			(hide yes)
			(effects
				(font
					(size 1 1)
					(thickness 0.15)
				)
				(justify mirror)
			)
		)
		(property "Manufacturer" "Bourns"
			(at 336.15 -27.65 0)
			(layer "B.Fab")
			(hide yes)
			(effects
				(font
					(size 1 1)
					(thickness 0.15)
				)
				(justify mirror)
			)
		)
		(property "Public" ""
			(at 336.15 -27.65 0)
			(layer "B.Fab")
			(hide yes)
			(effects
				(font
					(size 1 1)
					(thickness 0.15)
				)
				(justify mirror)
			)
		)
		(property "Tolerance" "1%"
			(at 336.15 -27.65 0)
			(layer "B.Fab")
			(hide yes)
			(effects
				(font
					(size 1 1)
					(thickness 0.15)
				)
				(justify mirror)
			)
		)
		(property "Val" "590R"
			(at 336.15 -27.65 0)
			(layer "B.Fab")
			(hide yes)
			(effects
				(font
					(size 1 1)
					(thickness 0.15)
				)
				(justify mirror)
			)
		)
		(sheetname "/Supply/")
		(sheetfile "supply.kicad_sch")
		(attr smd)
		(fp_rect
			(start -0.925 0.47)
			(end 0.925 -0.47)
			(stroke
				(width 0.05)
				(type default)
			)
			(fill no)
			(layer "B.CrtYd")
		)
		(fp_rect
			(start -0.5 0.25)
			(end 0.5 -0.25)
			(stroke
				(width 0.15)
				(type solid)
			)
			(fill no)
			(layer "B.Fab")
		)
		(fp_text user "License: Apache-2.0"
			(at -0.95 -5.169 270)
			(layer "B.Fab")
			(effects
				(font
					(size 0.7 0.7)
					(thickness 0.15)
				)
				(justify left bottom mirror)
			)
		)
		(fp_text user "${REFERENCE}"
			(at -0.95 -3.168 270)
			(layer "B.Fab")
			(effects
				(font
					(size 0.7 0.7)
					(thickness 0.15)
				)
				(justify left bottom mirror)
			)
		)
		(fp_text user "Author: Antmicro"
			(at -0.95 -4.169 270)
			(layer "B.Fab")
			(effects
				(font
					(size 0.7 0.7)
					(thickness 0.15)
				)
				(justify left bottom mirror)
			)
		)
		(pad "1" smd roundrect
			(at -0.48 0 90)
			(size 0.59 0.64)
			(layers "B.Cu" "B.Mask" "B.Paste")
			(roundrect_rratio 0.25)
			(net 650 "Net-(D5-A)")
			(pintype "passive")
		)
		(pad "2" smd roundrect
			(at 0.48 0 90)
			(size 0.59 0.64)
			(layers "B.Cu" "B.Mask" "B.Paste")
			(roundrect_rratio 0.25)
			(net 90 "+5V")
			(pintype "passive")
		)
	)
	(footprint "antmicro-footprints:R_0402_1005Metric"
		(layer "B.Cu")
		(at 211.6425 126.812 -90)
		(descr "Resistor SMD 0402")
		(tags "resistor SMD 0402")
		(property "Reference" "R38"
			(at 0.688 -0.3825 90)
			(layer "B.SilkS")
			(effects
				(font
					(size 0.7 0.7)
					(thickness 0.15)
				)
				(justify left bottom mirror)
			)
		)
		(property "Value" "R_49k9_0402"
			(at -1.011843 -1.772047 90)
			(layer "B.Fab")
			(hide yes)
			(effects
				(font
					(size 0.7 0.7)
					(thickness 0.15)
				)
				(justify left bottom mirror)
			)
		)
		(property "Datasheet" "https://www.bourns.com/docs/product-datasheets/cr.pdf"
			(at 0 0 270)
			(layer "F.Fab")
			(hide yes)
			(effects
				(font
					(size 1.27 1.27)
					(thickness 0.15)
				)
			)
		)
		(property "Description" "SMD Chip Resistor, 49.9 kohm, ± 1%, 63 mW, 0402 [1005 Metric], Thick Film, General Purpose"
			(at 0 0 270)
			(layer "F.Fab")
			(hide yes)
			(effects
				(font
					(size 1.27 1.27)
					(thickness 0.15)
				)
			)
		)
		(property "Author" "Antmicro"
			(at 84.8305 338.4545 0)
			(layer "B.Fab")
			(hide yes)
			(effects
				(font
					(size 1 1)
					(thickness 0.15)
				)
				(justify mirror)
			)
		)
		(property "License" "Apache-2.0"
			(at 84.8305 338.4545 0)
			(layer "B.Fab")
			(hide yes)
			(effects
				(font
					(size 1 1)
					(thickness 0.15)
				)
				(justify mirror)
			)
		)
		(property "MPN" "CR0402-FX-4992GLF"
			(at 84.8305 338.4545 0)
			(layer "B.Fab")
			(hide yes)
			(effects
				(font
					(size 1 1)
					(thickness 0.15)
				)
				(justify mirror)
			)
		)
		(property "Manufacturer" "Bourns"
			(at 84.8305 338.4545 0)
			(layer "B.Fab")
			(hide yes)
			(effects
				(font
					(size 1 1)
					(thickness 0.15)
				)
				(justify mirror)
			)
		)
		(property "Public" ""
			(at 84.8305 338.4545 0)
			(layer "B.Fab")
			(hide yes)
			(effects
				(font
					(size 1 1)
					(thickness 0.15)
				)
				(justify mirror)
			)
		)
		(property "Tolerance" "1%"
			(at 84.8305 338.4545 0)
			(layer "B.Fab")
			(hide yes)
			(effects
				(font
					(size 1 1)
					(thickness 0.15)
				)
				(justify mirror)
			)
		)
		(property "Val" "49k9"
			(at 84.8305 338.4545 0)
			(layer "B.Fab")
			(hide yes)
			(effects
				(font
					(size 1 1)
					(thickness 0.15)
				)
				(justify mirror)
			)
		)
		(sheetname "/Memory/")
		(sheetfile "memory.kicad_sch")
		(attr smd)
		(fp_rect
			(start -0.925 0.47)
			(end 0.925 -0.47)
			(stroke
				(width 0.05)
				(type default)
			)
			(fill no)
			(layer "B.CrtYd")
		)
		(fp_rect
			(start -0.5 0.25)
			(end 0.5 -0.25)
			(stroke
				(width 0.15)
				(type solid)
			)
			(fill no)
			(layer "B.Fab")
		)
		(fp_text user "Author: Antmicro"
			(at -0.95 -4.169 90)
			(layer "B.Fab")
			(effects
				(font
					(size 0.7 0.7)
					(thickness 0.15)
				)
				(justify left bottom mirror)
			)
		)
		(fp_text user "License: Apache-2.0"
			(at -0.95 -5.169 90)
			(layer "B.Fab")
			(effects
				(font
					(size 0.7 0.7)
					(thickness 0.15)
				)
				(justify left bottom mirror)
			)
		)
		(fp_text user "${REFERENCE}"
			(at -0.95 -3.168 90)
			(layer "B.Fab")
			(effects
				(font
					(size 0.7 0.7)
					(thickness 0.15)
				)
				(justify left bottom mirror)
			)
		)
		(pad "1" smd roundrect
			(at -0.48 0 270)
			(size 0.59 0.64)
			(layers "B.Cu" "B.Mask" "B.Paste")
			(roundrect_rratio 0.25)
			(net 208 "/FPGA MSSIO/EMMC.DAT0")
			(pintype "passive")
		)
		(pad "2" smd roundrect
			(at 0.48 0 270)
			(size 0.59 0.64)
			(layers "B.Cu" "B.Mask" "B.Paste")
			(roundrect_rratio 0.25)
			(net 137 "SD_VDD")
			(pintype "passive")
		)
	)
	(footprint "antmicro-footprints:R_0402_1005Metric"
		(layer "B.Cu")
		(at 218.975 137.775 180)
		(descr "Resistor SMD 0402")
		(tags "resistor SMD 0402")
		(property "Reference" "R50"
			(at 0.75 -0.475 0)
			(layer "B.SilkS")
			(effects
				(font
					(size 0.7 0.7)
					(thickness 0.15)
				)
				(justify left bottom mirror)
			)
		)
		(property "Value" "R_0R_0402"
			(at -1.011843 -1.772047 0)
			(layer "B.Fab")
			(hide yes)
			(effects
				(font
					(size 0.7 0.7)
					(thickness 0.15)
				)
				(justify left bottom mirror)
			)
		)
		(property "Datasheet" "https://industrial.panasonic.com/cdbs/www-data/pdf/RDA0000/AOA0000C301.pdf"
			(at 0 0 180)
			(layer "F.Fab")
			(hide yes)
			(effects
				(font
					(size 1.27 1.27)
					(thickness 0.15)
				)
			)
		)
		(property "Description" "SMD Chip Resistor, Jumper, 0 ohm, 100 mW, 0402 [1005 Metric], Thick Film, General Purpose"
			(at 0 0 180)
			(layer "F.Fab")
			(hide yes)
			(effects
				(font
					(size 1.27 1.27)
					(thickness 0.15)
				)
			)
		)
		(property "Author" "Antmicro"
			(at 437.95 275.55 0)
			(layer "B.Fab")
			(hide yes)
			(effects
				(font
					(size 1 1)
					(thickness 0.15)
				)
				(justify mirror)
			)
		)
		(property "Current" "1A"
			(at 437.95 275.55 0)
			(layer "B.Fab")
			(hide yes)
			(effects
				(font
					(size 1 1)
					(thickness 0.15)
				)
				(justify mirror)
			)
		)
		(property "License" "Apache-2.0"
			(at 437.95 275.55 0)
			(layer "B.Fab")
			(hide yes)
			(effects
				(font
					(size 1 1)
					(thickness 0.15)
				)
				(justify mirror)
			)
		)
		(property "MPN" "ERJ2GE0R00X"
			(at 437.95 275.55 0)
			(layer "B.Fab")
			(hide yes)
			(effects
				(font
					(size 1 1)
					(thickness 0.15)
				)
				(justify mirror)
			)
		)
		(property "Manufacturer" "Panasonic"
			(at 437.95 275.55 0)
			(layer "B.Fab")
			(hide yes)
			(effects
				(font
					(size 1 1)
					(thickness 0.15)
				)
				(justify mirror)
			)
		)
		(property "Public" ""
			(at 437.95 275.55 0)
			(layer "B.Fab")
			(hide yes)
			(effects
				(font
					(size 1 1)
					(thickness 0.15)
				)
				(justify mirror)
			)
		)
		(property "Tolerance" "~"
			(at 437.95 275.55 0)
			(layer "B.Fab")
			(hide yes)
			(effects
				(font
					(size 1 1)
					(thickness 0.15)
				)
				(justify mirror)
			)
		)
		(property "Val" "0R"
			(at 437.95 275.55 0)
			(layer "B.Fab")
			(hide yes)
			(effects
				(font
					(size 1 1)
					(thickness 0.15)
				)
				(justify mirror)
			)
		)
		(sheetname "/Memory/")
		(sheetfile "memory.kicad_sch")
		(attr smd)
		(fp_rect
			(start -0.925 0.47)
			(end 0.925 -0.47)
			(stroke
				(width 0.05)
				(type default)
			)
			(fill no)
			(layer "B.CrtYd")
		)
		(fp_rect
			(start -0.5 0.25)
			(end 0.5 -0.25)
			(stroke
				(width 0.15)
				(type solid)
			)
			(fill no)
			(layer "B.Fab")
		)
		(fp_text user "License: Apache-2.0"
			(at -0.95 -5.169 0)
			(layer "B.Fab")
			(effects
				(font
					(size 0.7 0.7)
					(thickness 0.15)
				)
				(justify left bottom mirror)
			)
		)
		(fp_text user "Author: Antmicro"
			(at -0.95 -4.169 0)
			(layer "B.Fab")
			(effects
				(font
					(size 0.7 0.7)
					(thickness 0.15)
				)
				(justify left bottom mirror)
			)
		)
		(fp_text user "${REFERENCE}"
			(at -0.95 -3.168 0)
			(layer "B.Fab")
			(effects
				(font
					(size 0.7 0.7)
					(thickness 0.15)
				)
				(justify left bottom mirror)
			)
		)
		(pad "1" smd roundrect
			(at -0.48 0 180)
			(size 0.59 0.64)
			(layers "B.Cu" "B.Mask" "B.Paste")
			(roundrect_rratio 0.25)
			(net 516 "Net-(R50-Pad1)")
			(pintype "passive")
		)
		(pad "2" smd roundrect
			(at 0.48 0 180)
			(size 0.59 0.64)
			(layers "B.Cu" "B.Mask" "B.Paste")
			(roundrect_rratio 0.25)
			(net 137 "SD_VDD")
			(pintype "passive")
		)
	)
	(footprint "antmicro-footprints:R_0402_1005Metric"
		(layer "B.Cu")
		(at 210.2 128.35)
		(descr "Resistor SMD 0402")
		(tags "resistor SMD 0402")
		(property "Reference" "R31"
			(at -0.8425 0.628 180)
			(layer "B.SilkS")
			(effects
				(font
					(size 0.7 0.7)
					(thickness 0.15)
				)
				(justify left bottom mirror)
			)
		)
		(property "Value" "R_49k9_0402"
			(at -1.011843 -1.772047 180)
			(layer "B.Fab")
			(hide yes)
			(effects
				(font
					(size 0.7 0.7)
					(thickness 0.15)
				)
				(justify left bottom mirror)
			)
		)
		(property "Datasheet" "https://www.bourns.com/docs/product-datasheets/cr.pdf"
			(at 0 0 0)
			(layer "F.Fab")
			(hide yes)
			(effects
				(font
					(size 1.27 1.27)
					(thickness 0.15)
				)
			)
		)
		(property "Description" "SMD Chip Resistor, 49.9 kohm, ± 1%, 63 mW, 0402 [1005 Metric], Thick Film, General Purpose"
			(at 0 0 0)
			(layer "F.Fab")
			(hide yes)
			(effects
				(font
					(size 1.27 1.27)
					(thickness 0.15)
				)
			)
		)
		(property "Author" "Antmicro"
			(at 0 0 0)
			(layer "B.Fab")
			(hide yes)
			(effects
				(font
					(size 1 1)
					(thickness 0.15)
				)
				(justify mirror)
			)
		)
		(property "License" "Apache-2.0"
			(at 0 0 0)
			(layer "B.Fab")
			(hide yes)
			(effects
				(font
					(size 1 1)
					(thickness 0.15)
				)
				(justify mirror)
			)
		)
		(property "MPN" "CR0402-FX-4992GLF"
			(at 0 0 0)
			(layer "B.Fab")
			(hide yes)
			(effects
				(font
					(size 1 1)
					(thickness 0.15)
				)
				(justify mirror)
			)
		)
		(property "Manufacturer" "Bourns"
			(at 0 0 0)
			(layer "B.Fab")
			(hide yes)
			(effects
				(font
					(size 1 1)
					(thickness 0.15)
				)
				(justify mirror)
			)
		)
		(property "Public" ""
			(at 0 0 0)
			(layer "B.Fab")
			(hide yes)
			(effects
				(font
					(size 1 1)
					(thickness 0.15)
				)
				(justify mirror)
			)
		)
		(property "Tolerance" "1%"
			(at 0 0 0)
			(layer "B.Fab")
			(hide yes)
			(effects
				(font
					(size 1 1)
					(thickness 0.15)
				)
				(justify mirror)
			)
		)
		(property "Val" "49k9"
			(at 0 0 0)
			(layer "B.Fab")
			(hide yes)
			(effects
				(font
					(size 1 1)
					(thickness 0.15)
				)
				(justify mirror)
			)
		)
		(sheetname "/Memory/")
		(sheetfile "memory.kicad_sch")
		(attr smd)
		(fp_rect
			(start -0.925 0.47)
			(end 0.925 -0.47)
			(stroke
				(width 0.05)
				(type default)
			)
			(fill no)
			(layer "B.CrtYd")
		)
		(fp_rect
			(start -0.5 0.25)
			(end 0.5 -0.25)
			(stroke
				(width 0.15)
				(type solid)
			)
			(fill no)
			(layer "B.Fab")
		)
		(fp_text user "Author: Antmicro"
			(at -0.95 -4.169 180)
			(layer "B.Fab")
			(effects
				(font
					(size 0.7 0.7)
					(thickness 0.15)
				)
				(justify left bottom mirror)
			)
		)
		(fp_text user "License: Apache-2.0"
			(at -0.95 -5.169 180)
			(layer "B.Fab")
			(effects
				(font
					(size 0.7 0.7)
					(thickness 0.15)
				)
				(justify left bottom mirror)
			)
		)
		(fp_text user "${REFERENCE}"
			(at -0.95 -3.168 180)
			(layer "B.Fab")
			(effects
				(font
					(size 0.7 0.7)
					(thickness 0.15)
				)
				(justify left bottom mirror)
			)
		)
		(pad "1" smd roundrect
			(at -0.48 0)
			(size 0.59 0.64)
			(layers "B.Cu" "B.Mask" "B.Paste")
			(roundrect_rratio 0.25)
			(net 214 "/FPGA MSSIO/EMMC.DAT7")
			(pintype "passive")
		)
		(pad "2" smd roundrect
			(at 0.48 0)
			(size 0.59 0.64)
			(layers "B.Cu" "B.Mask" "B.Paste")
			(roundrect_rratio 0.25)
			(net 137 "SD_VDD")
			(pintype "passive")
		)
	)
	(footprint "antmicro-footprints:C_0402_1005Metric"
		(layer "B.Cu")
		(at 203.375 146.95 -135)
		(descr "Capacitor SMD 0402")
		(tags "capacitor SMD 0402")
		(property "Reference" "C215"
			(at -8.085766 5.617963 225)
			(layer "B.SilkS")
			(effects
				(font
					(size 0.7 0.7)
					(thickness 0.15)
				)
				(justify left bottom mirror)
			)
		)
		(property "Value" "C_100n_0402"
			(at -1.022927 -2.155213 45)
			(layer "B.Fab")
			(hide yes)
			(effects
				(font
					(size 0.7 0.7)
					(thickness 0.15)
				)
				(justify left bottom mirror)
			)
		)
		(property "Datasheet" "https://www.murata.com/products/productdetail?partno=GRM155R61H104KE14%23"
			(at 0 0 225)
			(layer "F.Fab")
			(hide yes)
			(effects
				(font
					(size 1.27 1.27)
					(thickness 0.15)
				)
			)
		)
		(property "Description" "SMD Multilayer Ceramic Capacitor, 0.1 µF, 50 V, 0402 [1005 Metric], ± 10%, X5R, GRM Series"
			(at 0 0 225)
			(layer "F.Fab")
			(hide yes)
			(effects
				(font
					(size 1.27 1.27)
					(thickness 0.15)
				)
			)
		)
		(property "Author" "Antmicro"
			(at 243.2735 394.667183 0)
			(layer "B.Fab")
			(hide yes)
			(effects
				(font
					(size 1 1)
					(thickness 0.15)
				)
				(justify mirror)
			)
		)
		(property "Dielectric" "X5R"
			(at 243.2735 394.667183 0)
			(layer "B.Fab")
			(hide yes)
			(effects
				(font
					(size 1 1)
					(thickness 0.15)
				)
				(justify mirror)
			)
		)
		(property "License" "Apache-2.0"
			(at 243.2735 394.667183 0)
			(layer "B.Fab")
			(hide yes)
			(effects
				(font
					(size 1 1)
					(thickness 0.15)
				)
				(justify mirror)
			)
		)
		(property "MPN" "GRM155R61H104KE14D"
			(at 243.2735 394.667183 0)
			(layer "B.Fab")
			(hide yes)
			(effects
				(font
					(size 1 1)
					(thickness 0.15)
				)
				(justify mirror)
			)
		)
		(property "Manufacturer" "Murata"
			(at 243.2735 394.667183 0)
			(layer "B.Fab")
			(hide yes)
			(effects
				(font
					(size 1 1)
					(thickness 0.15)
				)
				(justify mirror)
			)
		)
		(property "Public" ""
			(at 243.2735 394.667183 0)
			(layer "B.Fab")
			(hide yes)
			(effects
				(font
					(size 1 1)
					(thickness 0.15)
				)
				(justify mirror)
			)
		)
		(property "Val" "100n"
			(at 243.2735 394.667183 0)
			(layer "B.Fab")
			(hide yes)
			(effects
				(font
					(size 1 1)
					(thickness 0.15)
				)
				(justify mirror)
			)
		)
		(property "Voltage" "50V"
			(at 243.2735 394.667183 0)
			(layer "B.Fab")
			(hide yes)
			(effects
				(font
					(size 1 1)
					(thickness 0.15)
				)
				(justify mirror)
			)
		)
		(sheetname "/MIPI CrossLink/")
		(sheetfile "crosslink.kicad_sch")
		(attr smd)
		(fp_poly
			(pts
				(xy -0.925 0.47) (xy 0.925 0.47) (xy 0.925 -0.47) (xy -0.925 -0.47)
			)
			(stroke
				(width 0.05)
				(type default)
			)
			(fill no)
			(layer "B.CrtYd")
		)
		(fp_line
			(start 0.504 0.25)
			(end 0.504 -0.248)
			(stroke
				(width 0.15)
				(type solid)
			)
			(layer "B.Fab")
		)
		(fp_line
			(start 0.504 -0.248)
			(end -0.494 -0.248)
			(stroke
				(width 0.15)
				(type solid)
			)
			(layer "B.Fab")
		)
		(fp_line
			(start -0.494 0.25)
			(end 0.504 0.25)
			(stroke
				(width 0.15)
				(type solid)
			)
			(layer "B.Fab")
		)
		(fp_line
			(start -0.494 -0.248)
			(end -0.494 0.25)
			(stroke
				(width 0.15)
				(type solid)
			)
			(layer "B.Fab")
		)
		(fp_text user "${REFERENCE}"
			(at -0.939 -4.599 45)
			(layer "B.Fab")
			(effects
				(font
					(size 0.7 0.7)
					(thickness 0.15)
				)
				(justify left bottom mirror)
			)
		)
		(fp_text user "License: Apache-2.0"
			(at -0.939 -5.799 45)
			(layer "B.Fab")
			(effects
				(font
					(size 0.7 0.7)
					(thickness 0.15)
				)
				(justify left bottom mirror)
			)
		)
		(fp_text user "Author: Antmicro"
			(at -0.939 -3.399 45)
			(layer "B.Fab")
			(effects
				(font
					(size 0.7 0.7)
					(thickness 0.15)
				)
				(justify left bottom mirror)
			)
		)
		(pad "1" smd roundrect
			(at -0.48 0 225)
			(size 0.59 0.64)
			(layers "B.Cu" "B.Mask" "B.Paste")
			(roundrect_rratio 0.25)
			(net 417 "GND")
			(pintype "passive")
		)
		(pad "2" smd roundrect
			(at 0.48 0 225)
			(size 0.59 0.64)
			(layers "B.Cu" "B.Mask" "B.Paste")
			(roundrect_rratio 0.25)
			(net 176 "/MIPI CrossLink/CL_VCC")
			(pintype "passive")
		)
	)
)
